(kicad_pcb
	(version 20240108)
	(generator "pcbnew")
	(generator_version "8.0")
	(general
		(thickness 1.62)
		(legacy_teardrops no)
	)
	(paper "A4")
	(title_block
		(title "Jetson Orin Baseboard")
		(date "2025-03-12")
		(rev "1.3.4")
		(company "Antmicro Ltd")
		(comment 1 "www.antmicro.com")
		(comment 9 "footprints 90-93 of 677")
	)
	(layers
		(0 "F.Cu" signal)
		(1 "In1.Cu" signal)
		(2 "In2.Cu" signal)
		(3 "In3.Cu" signal)
		(4 "In4.Cu" jumper)
		(5 "In5.Cu" signal)
		(6 "In6.Cu" signal)
		(31 "B.Cu" signal)
		(32 "B.Adhes" user "B.Adhesive")
		(33 "F.Adhes" user "F.Adhesive")
		(34 "B.Paste" user)
		(35 "F.Paste" user)
		(36 "B.SilkS" user "B.Silkscreen")
		(37 "F.SilkS" user "F.Silkscreen")
		(38 "B.Mask" user)
		(39 "F.Mask" user)
		(40 "Dwgs.User" user "User.Drawings")
		(41 "Cmts.User" user "User.Comments")
		(42 "Eco1.User" user "User.Eco1")
		(43 "Eco2.User" user "User.Eco2")
		(44 "Edge.Cuts" user)
		(45 "Margin" user)
		(46 "B.CrtYd" user "B.Courtyard")
		(47 "F.CrtYd" user "F.Courtyard")
		(48 "B.Fab" user)
		(49 "F.Fab" user)
	)
	(footprint "antmicro-footprints:XDFN-2_1x0.60mm"
		(layer "F.Cu")
		(at 137.8 87.45 -90)
		(property "Reference" "D42"
			(at 0.298 -0.402 180)
			(layer "F.SilkS")
			(effects
				(font
					(size 0.7 0.7)
					(thickness 0.15)
				)
				(justify left bottom)
			)
		)
		(property "Value" "TPD1E0B04_XDFN-2"
			(at 0 1.5 -90)
			(layer "F.Fab")
			(effects
				(font
					(size 0.7 0.7)
					(thickness 0.15)
				)
				(justify left bottom)
			)
		)
		(property "Footprint" "antmicro-footprints:XDFN-2_1x0.60mm"
			(at 0 0 -90)
			(layer "F.Fab")
			(hide yes)
			(effects
				(font
					(size 1.27 1.27)
					(thickness 0.15)
				)
			)
		)
		(property "Datasheet" "https://www.ti.com/general/docs/suppproductinfo.tsp?distId=26&gotoUrl=https://www.ti.com/lit/gpn/tpd1e0b04"
			(at 0 0 -90)
			(layer "F.Fab")
			(hide yes)
			(effects
				(font
					(size 1.27 1.27)
					(thickness 0.15)
				)
			)
		)
		(property "MPN" "TPD1E0B04DPYR"
			(at 50.35 225.25 0)
			(layer "F.Fab")
			(hide yes)
			(effects
				(font
					(size 1 1)
					(thickness 0.15)
				)
			)
		)
		(property "Manufacturer" "Texas Instruments"
			(at 50.35 225.25 0)
			(layer "F.Fab")
			(hide yes)
			(effects
				(font
					(size 1 1)
					(thickness 0.15)
				)
			)
		)
		(property "Author" "Antmicro"
			(at 50.35 225.25 0)
			(layer "F.Fab")
			(hide yes)
			(effects
				(font
					(size 1 1)
					(thickness 0.15)
				)
			)
		)
		(property "License" "Apache-2.0"
			(at 50.35 225.25 0)
			(layer "F.Fab")
			(hide yes)
			(effects
				(font
					(size 1 1)
					(thickness 0.15)
				)
			)
		)
		(sheetname "Peripherals")
		(sheetfile "peripherals.kicad_sch")
		(attr smd)
		(fp_rect
			(start -0.725 -0.475)
			(end 0.725 0.475)
			(stroke
				(width 0.05)
				(type solid)
			)
			(fill none)
			(layer "F.CrtYd")
		)
		(fp_rect
			(start -0.55 -0.35)
			(end 0.55 0.35)
			(stroke
				(width 0.15)
				(type solid)
			)
			(fill none)
			(layer "F.Fab")
		)
		(fp_text user "Author: Antmicro"
			(at -0.8 4.4 -90)
			(layer "F.Fab")
			(hide yes)
			(effects
				(font
					(size 0.7 0.7)
					(thickness 0.15)
				)
				(justify left bottom)
			)
		)
		(fp_text user "License: Apache-2.0"
			(at -0.8 5.6 -90)
			(layer "F.Fab")
			(hide yes)
			(effects
				(font
					(size 0.7 0.7)
					(thickness 0.15)
				)
				(justify left bottom)
			)
		)
		(fp_text user "${REFERENCE}"
			(at -0.8 3.2 -90)
			(layer "F.Fab")
			(hide yes)
			(effects
				(font
					(size 0.7 0.7)
					(thickness 0.15)
				)
				(justify left bottom)
			)
		)
		(pad "1" smd roundrect
			(at -0.351 0 270)
			(size 0.3 0.5)
			(layers "F.Cu" "F.Paste" "F.Mask")
			(roundrect_rratio 0.25)
			(net 412 "/Peripherals/PCIE2_TX0_CONN_P")
			(pinfunction "C")
			(pintype "passive")
		)
		(pad "2" smd roundrect
			(at 0.349 0 270)
			(size 0.3 0.5)
			(layers "F.Cu" "F.Paste" "F.Mask")
			(roundrect_rratio 0.25)
			(net 1 "GND")
			(pinfunction "A")
			(pintype "passive")
		)
	)
	(footprint "antmicro-footprints:R_0402_1005Metric"
		(layer "F.Cu")
		(at 114.4 100.8 180)
		(descr "Resistor SMD 0402")
		(tags "resistor SMD 0402")
		(property "Reference" "R31"
			(at 3.05 -0.475 180)
			(layer "F.SilkS")
			(effects
				(font
					(size 0.7 0.7)
					(thickness 0.15)
				)
				(justify left bottom)
			)
		)
		(property "Value" "R_0R_0402"
			(at 0 1.4 180)
			(layer "F.Fab")
			(effects
				(font
					(size 0.7 0.7)
					(thickness 0.15)
				)
				(justify left bottom)
			)
		)
		(property "Footprint" "antmicro-footprints:R_0402_1005Metric"
			(at 0 0 180)
			(layer "F.Fab")
			(hide yes)
			(effects
				(font
					(size 1.27 1.27)
					(thickness 0.15)
				)
			)
		)
		(property "Datasheet" "https://industrial.panasonic.com/cdbs/www-data/pdf/RDA0000/AOA0000C301.pdf"
			(at 0 0 180)
			(layer "F.Fab")
			(hide yes)
			(effects
				(font
					(size 1.27 1.27)
					(thickness 0.15)
				)
			)
		)
		(property "Author" "Antmicro"
			(at 228.8 201.6 0)
			(layer "F.Fab")
			(hide yes)
			(effects
				(font
					(size 1 1)
					(thickness 0.15)
				)
			)
		)
		(property "Current" "1A"
			(at 228.8 201.6 0)
			(layer "F.Fab")
			(hide yes)
			(effects
				(font
					(size 1 1)
					(thickness 0.15)
				)
			)
		)
		(property "License" "Apache-2.0"
			(at 228.8 201.6 0)
			(layer "F.Fab")
			(hide yes)
			(effects
				(font
					(size 1 1)
					(thickness 0.15)
				)
			)
		)
		(property "MPN" "ERJ2GE0R00X"
			(at 228.8 201.6 0)
			(layer "F.Fab")
			(hide yes)
			(effects
				(font
					(size 1 1)
					(thickness 0.15)
				)
			)
		)
		(property "Manufacturer" "Panasonic"
			(at 228.8 201.6 0)
			(layer "F.Fab")
			(hide yes)
			(effects
				(font
					(size 1 1)
					(thickness 0.15)
				)
			)
		)
		(property "Tolerance" ""
			(at 228.8 201.6 0)
			(layer "F.Fab")
			(hide yes)
			(effects
				(font
					(size 1 1)
					(thickness 0.15)
				)
			)
		)
		(property "Val" "0R"
			(at 228.8 201.6 0)
			(layer "F.Fab")
			(hide yes)
			(effects
				(font
					(size 1 1)
					(thickness 0.15)
				)
			)
		)
		(sheetname "M.2")
		(sheetfile "m-2.kicad_sch")
		(attr smd exclude_from_pos_files exclude_from_bom dnp)
		(fp_rect
			(start -0.925 -0.47)
			(end 0.925 0.47)
			(stroke
				(width 0.05)
				(type default)
			)
			(fill none)
			(layer "F.CrtYd")
		)
		(fp_rect
			(start -0.5 -0.25)
			(end 0.5 0.25)
			(stroke
				(width 0.15)
				(type solid)
			)
			(fill none)
			(layer "F.Fab")
		)
		(fp_text user "License: Apache-2.0"
			(at -0.95 5.169 180)
			(layer "F.Fab")
			(hide yes)
			(effects
				(font
					(size 0.7 0.7)
					(thickness 0.15)
				)
				(justify left bottom)
			)
		)
		(fp_text user "${REFERENCE}"
			(at -0.95 3.168 180)
			(layer "F.Fab")
			(hide yes)
			(effects
				(font
					(size 0.7 0.7)
					(thickness 0.15)
				)
				(justify left bottom)
			)
		)
		(fp_text user "Author: Antmicro"
			(at -0.95 4.169 180)
			(layer "F.Fab")
			(hide yes)
			(effects
				(font
					(size 0.7 0.7)
					(thickness 0.15)
				)
				(justify left bottom)
			)
		)
		(pad "1" smd roundrect
			(at -0.48 0 180)
			(size 0.59 0.64)
			(layers "F.Cu" "F.Paste" "F.Mask")
			(roundrect_rratio 0.25)
			(net 223 "/M.2/M2_E_I2C_CLK")
			(pintype "passive")
		)
		(pad "2" smd roundrect
			(at 0.48 0 180)
			(size 0.59 0.64)
			(layers "F.Cu" "F.Paste" "F.Mask")
			(roundrect_rratio 0.25)
			(net 252 "SYS_SCL")
			(pintype "passive")
		)
	)
	(footprint "antmicro-footprints:USON-10_2.5x1mm_P0.5mm"
		(layer "F.Cu")
		(at 131.7 108.65)
		(descr "USON-10 2.5x1mm_ Pitch 0.5mm")
		(tags "USON-10 2.5x1mm Pitch 0.5mm")
		(property "Reference" "U30"
			(at 1.82 0.98 90)
			(layer "F.SilkS")
			(effects
				(font
					(size 0.7 0.7)
					(thickness 0.15)
				)
				(justify left bottom)
			)
		)
		(property "Value" "TPD4E05U06QDQARQ1"
			(at 0.018 2.499 0)
			(layer "F.Fab")
			(effects
				(font
					(size 0.7 0.7)
					(thickness 0.15)
				)
				(justify left bottom)
			)
		)
		(property "Footprint" "antmicro-footprints:USON-10_2.5x1mm_P0.5mm"
			(at 0 0 0)
			(layer "F.Fab")
			(hide yes)
			(effects
				(font
					(size 1.27 1.27)
					(thickness 0.15)
				)
			)
		)
		(property "Datasheet" "https://www.ti.com/lit/ds/symlink/tpd4e05u06-q1.pdf?HQS=dis-mous-null-mousermode-dsf-pf-null-wwe&ts=1663591265741&ref_url=https%253A%252F%252Fwww.mouser.com%252F"
			(at 0 0 0)
			(layer "F.Fab")
			(hide yes)
			(effects
				(font
					(size 1.27 1.27)
					(thickness 0.15)
				)
			)
		)
		(property "Author" "Antmicro"
			(at 0 0 0)
			(layer "F.Fab")
			(hide yes)
			(effects
				(font
					(size 1 1)
					(thickness 0.15)
				)
			)
		)
		(property "License" "Apache-2.0"
			(at 0 0 0)
			(layer "F.Fab")
			(hide yes)
			(effects
				(font
					(size 1 1)
					(thickness 0.15)
				)
			)
		)
		(property "MPN" "TPD4E05U06QDQARQ1"
			(at 0 0 0)
			(layer "F.Fab")
			(hide yes)
			(effects
				(font
					(size 1 1)
					(thickness 0.15)
				)
			)
		)
		(property "Manufacturer" "Texas Instruments"
			(at 0 0 0)
			(layer "F.Fab")
			(hide yes)
			(effects
				(font
					(size 1 1)
					(thickness 0.15)
				)
			)
		)
		(sheetname "Peripherals")
		(sheetfile "peripherals.kicad_sch")
		(attr smd)
		(fp_line
			(start 0.498 -1.401)
			(end -0.5 -1.401)
			(stroke
				(width 0.15)
				(type solid)
			)
			(layer "F.SilkS")
		)
		(fp_line
			(start 0.498 1.398)
			(end -0.5 1.398)
			(stroke
				(width 0.15)
				(type solid)
			)
			(layer "F.SilkS")
		)
		(fp_circle
			(center -0.68 -1.27)
			(end -0.63 -1.27)
			(stroke
				(width 0.15)
				(type solid)
			)
			(fill solid)
			(layer "F.SilkS")
		)
		(fp_rect
			(start -0.8 -1.5)
			(end 0.8 1.499)
			(stroke
				(width 0.05)
				(type solid)
			)
			(fill none)
			(layer "F.CrtYd")
		)
		(fp_line
			(start -0.5 -1)
			(end -0.5 1.249)
			(stroke
				(width 0.15)
				(type solid)
			)
			(layer "F.Fab")
		)
		(fp_line
			(start -0.5 1.249)
			(end 0.498 1.249)
			(stroke
				(width 0.15)
				(type solid)
			)
			(layer "F.Fab")
		)
		(fp_line
			(start -0.25 -1.25)
			(end -0.5 -1)
			(stroke
				(width 0.15)
				(type solid)
			)
			(layer "F.Fab")
		)
		(fp_line
			(start 0.498 -1.25)
			(end -0.25 -1.25)
			(stroke
				(width 0.15)
				(type solid)
			)
			(layer "F.Fab")
		)
		(fp_line
			(start 0.498 -1.25)
			(end 0.498 1.249)
			(stroke
				(width 0.15)
				(type solid)
			)
			(layer "F.Fab")
		)
		(fp_text user "Author: Antmicro"
			(at -0.802 5.7 0)
			(layer "F.Fab")
			(hide yes)
			(effects
				(font
					(size 0.7 0.7)
					(thickness 0.15)
				)
				(justify left bottom)
			)
		)
		(fp_text user "License: Apache-2.0"
			(at -0.802 6.9 0)
			(layer "F.Fab")
			(hide yes)
			(effects
				(font
					(size 0.7 0.7)
					(thickness 0.15)
				)
				(justify left bottom)
			)
		)
		(fp_text user "${REFERENCE}"
			(at -0.802 4.498 0)
			(layer "F.Fab")
			(hide yes)
			(effects
				(font
					(size 0.7 0.7)
					(thickness 0.15)
				)
				(justify left bottom)
			)
		)
		(pad "1" smd roundrect
			(at -0.387 -1 270)
			(size 0.25 0.55)
			(layers "F.Cu" "F.Paste" "F.Mask")
			(roundrect_rratio 0.25)
			(net 251 "SYS_SDA")
			(pintype "passive")
		)
		(pad "2" smd roundrect
			(at -0.387 -0.5 270)
			(size 0.25 0.55)
			(layers "F.Cu" "F.Paste" "F.Mask")
			(roundrect_rratio 0.25)
			(net 252 "SYS_SCL")
			(pintype "passive")
		)
		(pad "3" smd roundrect
			(at -0.387 0 270)
			(size 0.4 0.55)
			(layers "F.Cu" "F.Paste" "F.Mask")
			(roundrect_rratio 0.25)
			(net 1 "GND")
			(pintype "power_in")
		)
		(pad "4" smd roundrect
			(at -0.387 0.498 270)
			(size 0.25 0.55)
			(layers "F.Cu" "F.Paste" "F.Mask")
			(roundrect_rratio 0.25)
			(net 130 "I2C2_SDA")
			(pintype "passive")
		)
		(pad "5" smd roundrect
			(at -0.387 0.998 270)
			(size 0.25 0.55)
			(layers "F.Cu" "F.Paste" "F.Mask")
			(roundrect_rratio 0.25)
			(net 129 "I2C2_SCL")
			(pintype "passive")
		)
		(pad "6" smd roundrect
			(at 0.385 0.998 270)
			(size 0.25 0.55)
			(layers "F.Cu" "F.Paste" "F.Mask")
			(roundrect_rratio 0.25)
			(net 129 "I2C2_SCL")
			(pintype "passive")
		)
		(pad "7" smd roundrect
			(at 0.385 0.498 270)
			(size 0.25 0.55)
			(layers "F.Cu" "F.Paste" "F.Mask")
			(roundrect_rratio 0.25)
			(net 130 "I2C2_SDA")
			(pintype "passive")
		)
		(pad "8" smd roundrect
			(at 0.385 0 270)
			(size 0.4 0.55)
			(layers "F.Cu" "F.Paste" "F.Mask")
			(roundrect_rratio 0.25)
			(net 1 "GND")
			(pintype "passive")
		)
		(pad "9" smd roundrect
			(at 0.385 -0.5 270)
			(size 0.25 0.55)
			(layers "F.Cu" "F.Paste" "F.Mask")
			(roundrect_rratio 0.25)
			(net 252 "SYS_SCL")
			(pintype "passive")
		)
		(pad "10" smd roundrect
			(at 0.385 -1 270)
			(size 0.25 0.55)
			(layers "F.Cu" "F.Paste" "F.Mask")
			(roundrect_rratio 0.25)
			(net 251 "SYS_SDA")
			(pintype "passive")
		)
	)
	(footprint "antmicro-footprints:SOT-363"
		(layer "F.Cu")
		(at 58.1 109.2)
		(property "Reference" "Q13"
			(at -3.45 -1.025 0)
			(layer "F.SilkS")
			(effects
				(font
					(size 0.7 0.7)
					(thickness 0.15)
				)
				(justify left bottom)
			)
		)
		(property "Value" "BCM857BS-7-F"
			(at 0 2.2 0)
			(layer "F.Fab")
			(effects
				(font
					(size 0.7 0.7)
					(thickness 0.15)
				)
				(justify left bottom)
			)
		)
		(property "Footprint" "antmicro-footprints:SOT-363"
			(at 0 0 0)
			(layer "F.Fab")
			(hide yes)
			(effects
				(font
					(size 1.27 1.27)
					(thickness 0.15)
				)
			)
		)
		(property "Datasheet" "https://www.diodes.com/assets/Datasheets/BCM857BS.pdf"
			(at 0 0 0)
			(layer "F.Fab")
			(hide yes)
			(effects
				(font
					(size 1.27 1.27)
					(thickness 0.15)
				)
			)
		)
		(property "Author" "Antmicro"
			(at 0 0 0)
			(layer "F.Fab")
			(hide yes)
			(effects
				(font
					(size 1 1)
					(thickness 0.15)
				)
			)
		)
		(property "License" "Apache-2.0"
			(at 0 0 0)
			(layer "F.Fab")
			(hide yes)
			(effects
				(font
					(size 1 1)
					(thickness 0.15)
				)
			)
		)
		(property "MPN" "BCM857BS-7-F"
			(at 0 0 0)
			(layer "F.Fab")
			(hide yes)
			(effects
				(font
					(size 1 1)
					(thickness 0.15)
				)
			)
		)
		(property "Manufacturer" "Diodes Incorporated"
			(at 0 0 0)
			(layer "F.Fab")
			(hide yes)
			(effects
				(font
					(size 1 1)
					(thickness 0.15)
				)
			)
		)
		(sheetname "Supply")
		(sheetfile "supply.kicad_sch")
		(attr smd)
		(fp_line
			(start -0.8 1.146)
			(end -0.8 1.223)
			(stroke
				(width 0.15)
				(type solid)
			)
			(layer "F.SilkS")
		)
		(fp_line
			(start -0.8 1.223)
			(end 0.803 1.223)
			(stroke
				(width 0.15)
				(type solid)
			)
			(layer "F.SilkS")
		)
		(fp_line
			(start -0.72 -1.153)
			(end -0.72 -1.228)
			(stroke
				(width 0.15)
				(type solid)
			)
			(layer "F.SilkS")
		)
		(fp_line
			(start 0.803 -1.228)
			(end -0.72 -1.228)
			(stroke
				(width 0.15)
				(type solid)
			)
			(layer "F.SilkS")
		)
		(fp_line
			(start 0.803 -1.153)
			(end 0.803 -1.228)
			(stroke
				(width 0.15)
				(type solid)
			)
			(layer "F.SilkS")
		)
		(fp_line
			(start 0.803 1.146)
			(end 0.803 1.223)
			(stroke
				(width 0.15)
				(type solid)
			)
			(layer "F.SilkS")
		)
		(fp_circle
			(center -0.978102 -1.2)
			(end -0.928102 -1.2)
			(stroke
				(width 0.15)
				(type solid)
			)
			(fill solid)
			(layer "F.SilkS")
		)
		(fp_rect
			(start 1.3 -1.3)
			(end -1.3 1.3)
			(stroke
				(width 0.05)
				(type solid)
			)
			(fill none)
			(layer "F.CrtYd")
		)
		(fp_line
			(start -0.1 -1.1)
			(end -0.68 -0.52)
			(stroke
				(width 0.15)
				(type solid)
			)
			(layer "F.Fab")
		)
		(fp_rect
			(start 0.68 1.1)
			(end -0.68 -1.1)
			(stroke
				(width 0.15)
				(type solid)
			)
			(fill none)
			(layer "F.Fab")
		)
		(fp_text user "Author: Antmicro"
			(at -1.3 6.4 0)
			(layer "F.Fab")
			(hide yes)
			(effects
				(font
					(size 0.7 0.7)
					(thickness 0.15)
				)
				(justify left bottom)
			)
		)
		(fp_text user "${REFERENCE}"
			(at -1.3 4 0)
			(layer "F.Fab")
			(hide yes)
			(effects
				(font
					(size 0.7 0.7)
					(thickness 0.15)
				)
				(justify left bottom)
			)
		)
		(fp_text user "License: Apache-2.0"
			(at -1.3 5.2 0)
			(layer "F.Fab")
			(hide yes)
			(effects
				(font
					(size 0.7 0.7)
					(thickness 0.15)
				)
				(justify left bottom)
			)
		)
		(pad "1" smd custom
			(at -0.948 -0.752 270)
			(size 0.6 0.6)
			(layers "F.Cu" "F.Paste" "F.Mask")
			(net 328 "/Supply/VCC_IN")
			(pintype "passive")
			(options
				(clearance outline)
				(anchor rect)
			)
			(primitives)
		)
		(pad "2" smd rect
			(at -0.948 -0.002 270)
			(size 0.4 0.6)
			(layers "F.Cu" "F.Paste" "F.Mask")
			(net 717 "Net-(Q13-Pad2)")
			(pintype "passive")
		)
		(pad "3" smd custom
			(at -0.948 0.745 270)
			(size 0.6 0.6)
			(layers "F.Cu" "F.Paste" "F.Mask")
			(net 717 "Net-(Q13-Pad2)")
			(pintype "passive")
			(options
				(clearance outline)
				(anchor rect)
			)
			(primitives)
		)
		(pad "4" smd custom
			(at 0.951 0.745 270)
			(size 0.6 0.6)
			(layers "F.Cu" "F.Paste" "F.Mask")
			(net 189 "Net-(D28-C)")
			(pintype "passive")
			(options
				(clearance outline)
				(anchor rect)
			)
			(primitives)
		)
		(pad "5" smd rect
			(at 0.951 -0.002 270)
			(size 0.4 0.6)
			(layers "F.Cu" "F.Paste" "F.Mask")
			(net 717 "Net-(Q13-Pad2)")
			(pintype "passive")
		)
		(pad "6" smd custom
			(at 0.951 -0.752 270)
			(size 0.6 0.6)
			(layers "F.Cu" "F.Paste" "F.Mask")
			(net 630 "Net-(Q15-G)")
			(pintype "passive")
			(options
				(clearance outline)
				(anchor rect)
			)
			(primitives)
		)
	)
)
